(kicad_pcb
	(version 20260206)
	(generator "pcbnew")
	(generator_version "10.0")
	(general
		(thickness 1.6)
		(legacy_teardrops no)
	)
	(paper "A4")
	(title_block
		(title "Bryce Canyon_F.DPB_16315-1-OCP.brd")
		(comment 1 "Bryce Canyon / footprints 215-217 of 2223")
	)
	(layers
		(0 "F.Cu" signal "TOP")
		(4 "In1.Cu" signal "L2GND")
		(6 "In2.Cu" signal "L3")
		(8 "In3.Cu" signal "L4GND")
		(10 "In4.Cu" signal "L5")
		(12 "In5.Cu" signal "L6VCC")
		(14 "In6.Cu" signal "L7VCC")
		(16 "In7.Cu" signal "L8")
		(18 "In8.Cu" signal "L9GND")
		(20 "In9.Cu" signal "L10")
		(22 "In10.Cu" signal "L11GND")
		(2 "B.Cu" signal "BOTTOM")
		(9 "F.Adhes" user "F.Adhesive")
		(11 "B.Adhes" user "B.Adhesive")
		(13 "F.Paste" user "Package Geometry/Pastemask Top")
		(15 "B.Paste" user "Package Geometry/Pastemask Bottom")
		(5 "F.SilkS" user "Ref Des/Silkscreen Top")
		(7 "B.SilkS" user "Ref Des/Silkscreen Bottom")
		(1 "F.Mask" user "Board Geometry/Soldermask Top")
		(3 "B.Mask" user "Board Geometry/Soldermask Bottom")
		(17 "Dwgs.User" user "User.Drawings")
		(19 "Cmts.User" user "User.Comments")
		(21 "Eco1.User" user "User.Eco1")
		(23 "Eco2.User" user "User.Eco2")
		(25 "Edge.Cuts" user "Board Geometry/Outline")
		(27 "Margin" user)
		(31 "F.CrtYd" user "Package Geometry/Place Bound Top")
		(29 "B.CrtYd" user "Package Geometry/Place Bound Bottom")
		(35 "F.Fab" user "Ref Des/Assembly Top")
		(33 "B.Fab" user "Ref Des/Assembly Bottom")
	)
	(footprint ""
		(layer "F.Cu")
		(at 154.399996 -57.909968 -90)
		(property "Reference" "HDDSAS28"
			(at 0 0 270)
			(layer "F.SilkS")
			(hide yes)
			(effects
				(font
					(size 1.27 1.27)
				)
			)
		)
		(property "Value" "SKT-SAS15P-14P-45-GP"
			(at -20.7645 -8.9789 270)
			(unlocked yes)
			(layer "F.Fab")
			(hide yes)
			(effects
				(font
					(size 1.016 1.016)
					(thickness 0.1524)
				)
			)
		)
		(property "Device Type" "10120818-001C-TRLF"
			(at -20.7645 -10.5029 270)
			(unlocked yes)
			(layer "F.Fab")
			(hide yes)
			(effects
				(font
					(size 1.016 1.016)
					(thickness 0.1524)
				)
			)
		)
		(duplicate_pad_numbers_are_jumpers no)
		(fp_line
			(start 1.651 4.2926)
			(end 1.651 3.0099)
			(stroke
				(width 0.1524)
				(type default)
			)
			(layer "F.SilkS")
		)
		(fp_line
			(start 8.509 4.2926)
			(end 1.651 4.2926)
			(stroke
				(width 0.1524)
				(type default)
			)
			(layer "F.SilkS")
		)
		(fp_line
			(start -23.4188 3.0099)
			(end -23.4188 -3.2512)
			(stroke
				(width 0.1524)
				(type default)
			)
			(layer "F.SilkS")
		)
		(fp_line
			(start 1.651 3.0099)
			(end -23.4188 3.0099)
			(stroke
				(width 0.1524)
				(type default)
			)
			(layer "F.SilkS")
		)
		(fp_line
			(start 8.509 3.0099)
			(end 8.509 4.2926)
			(stroke
				(width 0.1524)
				(type default)
			)
			(layer "F.SilkS")
		)
		(fp_line
			(start 23.4188 3.0099)
			(end 8.509 3.0099)
			(stroke
				(width 0.1524)
				(type default)
			)
			(layer "F.SilkS")
		)
		(fp_line
			(start -23.4188 -3.2512)
			(end 23.4188 -3.2512)
			(stroke
				(width 0.1524)
				(type default)
			)
			(layer "F.SilkS")
		)
		(fp_line
			(start 23.4188 -3.2512)
			(end 23.4188 3.0099)
			(stroke
				(width 0.1524)
				(type default)
			)
			(layer "F.SilkS")
		)
		(fp_line
			(start 15.5067 -3.3401)
			(end 16.2687 -3.3401)
			(stroke
				(width 0.3302)
				(type default)
			)
			(layer "F.SilkS")
		)
		(fp_poly
			(pts
				(xy 15.868904 -3.230372) (xy 16.503904 -3.865372) (xy 15.233904 -3.865372)
			)
			(stroke
				(width 0)
				(type default)
			)
			(fill yes)
			(layer "F.SilkS")
		)
		(fp_poly
			(pts
				(xy -22.8727 -2.7559) (xy 22.8727 -2.7559) (xy 22.8727 2.7559) (xy 8.255 2.7559) (xy 8.255 3.5179)
				(xy 1.905 3.5179) (xy 1.905 2.7559) (xy -22.8727 2.7559)
			)
			(stroke
				(width 0)
				(type default)
			)
			(fill no)
			(layer "F.CrtYd")
		)
		(fp_poly
			(pts
				(xy 1.397 4.5466) (xy 1.397 3.2639) (xy -23.6728 3.2639) (xy -23.6728 -3.5052) (xy 23.6728 -3.5052)
				(xy 23.6728 -0.00635) (xy 22.8727 -0.00635) (xy 22.8727 -2.7559) (xy -22.8727 -2.7559) (xy -22.8727 2.7559)
				(xy 1.905 2.7559) (xy 1.905 3.5179) (xy 8.255 3.5179) (xy 8.255 2.7559) (xy 22.8727 2.7559) (xy 22.8727 0.00635)
				(xy 23.6728 0.00635) (xy 23.6728 3.2639) (xy 8.763 3.2639) (xy 8.763 4.5466)
			)
			(stroke
				(width 0)
				(type default)
			)
			(fill no)
			(layer "F.CrtYd")
		)
		(fp_poly
			(pts
				(xy 1.397 4.5466) (xy 1.397 3.2639) (xy -23.6728 3.2639) (xy -23.6728 -3.5052) (xy 23.6728 -3.5052)
				(xy 23.6728 3.2639) (xy 8.763 3.2639) (xy 8.763 4.5466)
			)
			(stroke
				(width 0)
				(type default)
			)
			(fill no)
			(layer "F.Fab")
		)
		(pad "" np_thru_hole circle
			(at -18.874994 0 270)
			(size 0.254 0.254)
			(drill 1.3462)
			(layers "*.Cu" "*.Mask")
			(clearance 0.9017)
			(thermal_gap 0.9017)
		)
		(pad "" np_thru_hole circle
			(at 18.874994 0 270)
			(size 0.254 0.254)
			(drill 0.9398)
			(layers "*.Cu" "*.Mask")
			(clearance 0.6985)
			(thermal_gap 0.6985)
		)
		(pad "G1" smd rect
			(at 21.874988 0 270)
			(size 2.5908 2.5908)
			(layers "F.Cu" "F.Mask" "F.Paste")
			(net "GND")
		)
		(pad "G2" smd rect
			(at -21.874988 0 270)
			(size 2.5908 2.5908)
			(layers "F.Cu" "F.Mask" "F.Paste")
			(net "GND")
		)
		(pad "P1" smd rect
			(at 1.905 -1.82499 270)
			(size 0.6096 2.3622)
			(layers "F.Cu" "F.Mask" "F.Paste")
			(net "Net_2071")
		)
		(pad "P2" smd rect
			(at 0.635 -1.82499 270)
			(size 0.6096 2.3622)
			(layers "F.Cu" "F.Mask" "F.Paste")
			(net "Net_2072")
		)
		(pad "P3" smd rect
			(at -0.635 -1.82499 270)
			(size 0.6096 2.3622)
			(layers "F.Cu" "F.Mask" "F.Paste")
			(net "Net_2073")
		)
		(pad "P4" smd rect
			(at -1.905 -1.82499 270)
			(size 0.6096 2.3622)
			(layers "F.Cu" "F.Mask" "F.Paste")
			(net "GND")
		)
		(pad "P5" smd rect
			(at -3.175 -1.82499 270)
			(size 0.6096 2.3622)
			(layers "F.Cu" "F.Mask" "F.Paste")
			(net "HDD_PRSNT_28")
		)
		(pad "P6" smd rect
			(at -4.445 -1.82499 270)
			(size 0.6096 2.3622)
			(layers "F.Cu" "F.Mask" "F.Paste")
			(net "GND")
		)
		(pad "P7" smd rect
			(at -5.715 -1.82499 270)
			(size 0.6096 2.3622)
			(layers "F.Cu" "F.Mask" "F.Paste")
			(net "5V_PRE_28")
		)
		(pad "P8" smd rect
			(at -6.985 -1.82499 270)
			(size 0.6096 2.3622)
			(layers "F.Cu" "F.Mask" "F.Paste")
			(net "P5V_HDD28")
		)
		(pad "P9" smd rect
			(at -8.255 -1.82499 270)
			(size 0.6096 2.3622)
			(layers "F.Cu" "F.Mask" "F.Paste")
			(net "P5V_HDD28")
		)
		(pad "P10" smd rect
			(at -9.525 -1.82499 270)
			(size 0.6096 2.3622)
			(layers "F.Cu" "F.Mask" "F.Paste")
			(net "GND")
		)
		(pad "P11" smd rect
			(at -10.795 -1.82499 270)
			(size 0.6096 2.3622)
			(layers "F.Cu" "F.Mask" "F.Paste")
			(net "ACT_HDD_28")
		)
		(pad "P12" smd rect
			(at -12.065 -1.82499 270)
			(size 0.6096 2.3622)
			(layers "F.Cu" "F.Mask" "F.Paste")
			(net "GND")
		)
		(pad "P13" smd rect
			(at -13.335 -1.82499 270)
			(size 0.6096 2.3622)
			(layers "F.Cu" "F.Mask" "F.Paste")
			(net "12V_PRE_28")
		)
		(pad "P14" smd rect
			(at -14.605 -1.82499 270)
			(size 0.6096 2.3622)
			(layers "F.Cu" "F.Mask" "F.Paste")
			(net "P12V_HDD28")
		)
		(pad "P15" smd rect
			(at -15.875 -1.82499 270)
			(size 0.6096 2.3622)
			(layers "F.Cu" "F.Mask" "F.Paste")
			(net "P12V_HDD28")
		)
		(pad "S1" smd rect
			(at 15.875 -1.82499 270)
			(size 0.6096 2.3622)
			(layers "F.Cu" "F.Mask" "F.Paste")
			(net "GND")
		)
		(pad "S2" smd rect
			(at 14.605 -1.82499 270)
			(size 0.6096 2.3622)
			(layers "F.Cu" "F.Mask" "F.Paste")
			(net "SAS_HDD_RX_P28")
		)
		(pad "S3" smd rect
			(at 13.335 -1.82499 270)
			(size 0.6096 2.3622)
			(layers "F.Cu" "F.Mask" "F.Paste")
			(net "SAS_HDD_RX_N28")
		)
		(pad "S4" smd rect
			(at 12.065 -1.82499 270)
			(size 0.6096 2.3622)
			(layers "F.Cu" "F.Mask" "F.Paste")
			(net "GND")
		)
		(pad "S5" smd rect
			(at 10.795 -1.82499 270)
			(size 0.6096 2.3622)
			(layers "F.Cu" "F.Mask" "F.Paste")
			(net "PHY_DRV_A_TO_SCC_A_28_DN")
		)
		(pad "S6" smd rect
			(at 9.525 -1.82499 270)
			(size 0.6096 2.3622)
			(layers "F.Cu" "F.Mask" "F.Paste")
			(net "PHY_DRV_A_TO_SCC_A_28_DP")
		)
		(pad "S7" smd rect
			(at 8.255 -1.82499 270)
			(size 0.6096 2.3622)
			(layers "F.Cu" "F.Mask" "F.Paste")
			(net "GND")
		)
		(pad "S8" smd rect
			(at 7.480046 2.845054 270)
			(size 0.508 2.3622)
			(layers "F.Cu" "F.Mask" "F.Paste")
			(net "GND")
		)
		(pad "S9" smd rect
			(at 6.679946 2.845054 270)
			(size 0.508 2.3622)
			(layers "F.Cu" "F.Mask" "F.Paste")
			(net "Net_466")
		)
		(pad "S10" smd rect
			(at 5.8801 2.845054 270)
			(size 0.508 2.3622)
			(layers "F.Cu" "F.Mask" "F.Paste")
			(net "Net_358")
		)
		(pad "S11" smd rect
			(at 5.08 2.845054 270)
			(size 0.508 2.3622)
			(layers "F.Cu" "F.Mask" "F.Paste")
			(net "GND")
		)
		(pad "S12" smd rect
			(at 4.2799 2.845054 270)
			(size 0.508 2.3622)
			(layers "F.Cu" "F.Mask" "F.Paste")
			(net "Net_394")
		)
		(pad "S13" smd rect
			(at 3.480054 2.845054 270)
			(size 0.508 2.3622)
			(layers "F.Cu" "F.Mask" "F.Paste")
			(net "Net_430")
		)
		(pad "S14" smd rect
			(at 2.679954 2.845054 270)
			(size 0.508 2.3622)
			(layers "F.Cu" "F.Mask" "F.Paste")
			(net "GND")
		)
		(zone
			(layer "F.Cu")
			(hatch none 0.5)
			(connect_pads
				(clearance 0)
			)
			(min_thickness 0.25)
			(keepout
				(tracks allowed)
				(vias not_allowed)
				(pads allowed)
				(copperpour not_allowed)
				(footprints allowed)
			)
			(placement
				(enabled no)
				(sheetname "")
			)
			(fill
				(thermal_gap 0.5)
				(thermal_bridge_width 0.5)
				(island_removal_mode 0)
			)
			(polygon
				(pts
					(xy 158.057596 -74.648568) (xy 150.983696 -74.648568) (xy 150.983696 -81.582768) (xy 152.088596 -81.582768)
					(xy 152.088596 -77.467968) (xy 156.711396 -77.467968) (xy 156.711396 -81.582768) (xy 158.057596 -81.582768)
				)
			)
		)
		(zone
			(layer "F.Cu")
			(hatch none 0.5)
			(connect_pads
				(clearance 0)
			)
			(min_thickness 0.25)
			(keepout
				(tracks not_allowed)
				(vias allowed)
				(pads allowed)
				(copperpour not_allowed)
				(footprints allowed)
			)
			(placement
				(enabled no)
				(sheetname "")
			)
			(fill
				(thermal_gap 0.5)
				(thermal_bridge_width 0.5)
				(island_removal_mode 0)
			)
			(polygon
				(pts
					(xy 158.057596 -74.648568) (xy 150.983696 -74.648568) (xy 150.983696 -81.582768) (xy 152.088596 -81.582768)
					(xy 152.088596 -77.467968) (xy 156.711396 -77.467968) (xy 156.711396 -81.582768) (xy 158.057596 -81.582768)
				)
			)
		)
		(zone
			(layer "F.Cu")
			(hatch none 0.5)
			(connect_pads
				(clearance 0)
			)
			(min_thickness 0.25)
			(keepout
				(tracks not_allowed)
				(vias allowed)
				(pads allowed)
				(copperpour not_allowed)
				(footprints allowed)
			)
			(placement
				(enabled no)
				(sheetname "")
			)
			(fill
				(thermal_gap 0.5)
				(thermal_bridge_width 0.5)
				(island_removal_mode 0)
			)
			(polygon
				(pts
					(xy 158.057596 -41.171368) (xy 150.983696 -41.171368) (xy 150.983696 -34.237168) (xy 152.088596 -34.237168)
					(xy 152.088596 -38.351968) (xy 156.711396 -38.351968) (xy 156.711396 -34.237168) (xy 158.057596 -34.237168)
				)
			)
		)
		(zone
			(layer "F.Cu")
			(hatch none 0.5)
			(connect_pads
				(clearance 0)
			)
			(min_thickness 0.25)
			(keepout
				(tracks allowed)
				(vias not_allowed)
				(pads allowed)
				(copperpour not_allowed)
				(footprints allowed)
			)
			(placement
				(enabled no)
				(sheetname "")
			)
			(fill
				(thermal_gap 0.5)
				(thermal_bridge_width 0.5)
				(island_removal_mode 0)
			)
			(polygon
				(pts
					(xy 158.057596 -41.171368) (xy 150.983696 -41.171368) (xy 150.983696 -34.237168) (xy 152.088596 -34.237168)
					(xy 152.088596 -38.351968) (xy 156.711396 -38.351968) (xy 156.711396 -34.237168) (xy 158.057596 -34.237168)
				)
			)
		)
		(zone
			(layers "F.Cu" "B.Cu" "In1.Cu" "In2.Cu" "In3.Cu" "In4.Cu" "In5.Cu" "In6.Cu"
				"In7.Cu" "In8.Cu" "In9.Cu" "In10.Cu"
			)
			(hatch none 0.5)
			(connect_pads
				(clearance 0)
			)
			(min_thickness 0.25)
			(keepout
				(tracks not_allowed)
				(vias allowed)
				(pads allowed)
				(copperpour not_allowed)
				(footprints allowed)
			)
			(placement
				(enabled no)
				(sheetname "")
			)
			(fill
				(thermal_gap 0.5)
				(thermal_bridge_width 0.5)
				(island_removal_mode 0)
			)
			(polygon
				(pts
					(arc
						(start 155.174696 -39.034974)
						(mid 153.625296 -39.034974)
						(end 155.174696 -39.034974)
					)
				)
			)
		)
		(zone
			(layers "F.Cu" "B.Cu" "In1.Cu" "In2.Cu" "In3.Cu" "In4.Cu" "In5.Cu" "In6.Cu"
				"In7.Cu" "In8.Cu" "In9.Cu" "In10.Cu"
			)
			(hatch none 0.5)
			(connect_pads
				(clearance 0)
			)
			(min_thickness 0.25)
			(keepout
				(tracks not_allowed)
				(vias allowed)
				(pads allowed)
				(copperpour not_allowed)
				(footprints allowed)
			)
			(placement
				(enabled no)
				(sheetname "")
			)
			(fill
				(thermal_gap 0.5)
				(thermal_bridge_width 0.5)
				(island_removal_mode 0)
			)
			(polygon
				(pts
					(arc
						(start 155.377896 -76.784962)
						(mid 153.422096 -76.784962)
						(end 155.377896 -76.784962)
					)
				)
			)
		)
	)
	(footprint ""
		(layer "F.Cu")
		(at 383.08915 -273.940016 90)
		(property "Reference" "VIA3"
			(at 0 0 90)
			(layer "F.SilkS")
			(hide yes)
			(effects
				(font
					(size 1.27 1.27)
				)
			)
		)
		(property "Value" "100OHM-8L-1D6MM-L18L16-GP"
			(at -3.7211 -4.5085 90)
			(unlocked yes)
			(layer "F.Fab")
			(hide yes)
			(effects
				(font
					(size 1.016 1.016)
					(thickness 0.1524)
				)
			)
		)
		(property "Device Type" "VIA-PCIE-4P-394076"
			(at -3.7211 -6.0325 90)
			(unlocked yes)
			(layer "F.Fab")
			(hide yes)
			(effects
				(font
					(size 1.016 1.016)
					(thickness 0.1524)
				)
			)
		)
		(duplicate_pad_numbers_are_jumpers no)
		(fp_rect
			(start -1.9685 0.381)
			(end 1.9685 -0.381)
			(stroke
				(width 0)
				(type default)
			)
			(fill no)
			(layer "F.CrtYd")
		)
		(fp_rect
			(start -1.9685 0.381)
			(end 1.9685 -0.381)
			(stroke
				(width 0)
				(type default)
			)
			(fill no)
			(layer "F.Fab")
		)
		(pad "1" thru_hole circle
			(at -1.5875 0 90)
			(size 0.508 0.508)
			(drill 0.254)
			(layers "*.Cu" "*.Mask")
			(remove_unused_layers no)
			(net "GND")
			(clearance 0.127)
			(thermal_gap 0.127)
		)
		(pad "2" thru_hole circle
			(at -0.5715 0 90)
			(size 0.508 0.508)
			(drill 0.254)
			(layers "*.Cu" "*.Mask")
			(remove_unused_layers no)
			(net "PHY_SCC_A_TO_DRV_A_8_DP")
			(clearance 0.127)
			(thermal_gap 0.127)
		)
		(pad "3" thru_hole circle
			(at 0.5715 0 90)
			(size 0.508 0.508)
			(drill 0.254)
			(layers "*.Cu" "*.Mask")
			(remove_unused_layers no)
			(net "PHY_SCC_A_TO_DRV_A_8_DN")
			(clearance 0.127)
			(thermal_gap 0.127)
		)
		(pad "4" thru_hole circle
			(at 1.5875 0 90)
			(size 0.508 0.508)
			(drill 0.254)
			(layers "*.Cu" "*.Mask")
			(remove_unused_layers no)
			(net "GND")
			(clearance 0.127)
			(thermal_gap 0.127)
		)
	)
	(footprint ""
		(layer "F.Cu")
		(at 23.732998 -177.270918)
		(property "Reference" "R405"
			(at 0 0 0)
			(layer "F.SilkS")
			(hide yes)
			(effects
				(font
					(size 1.27 1.27)
				)
			)
		)
		(property "Value" "2R6F-GP"
			(at -0.0508 -4.8514 0)
			(unlocked yes)
			(layer "F.Fab")
			(hide yes)
			(effects
				(font
					(size 1.016 1.016)
					(thickness 0.1524)
				)
			)
		)
		(property "Device Type" "R1206H26"
			(at 0 -6.3754 0)
			(unlocked yes)
			(layer "F.Fab")
			(hide yes)
			(effects
				(font
					(size 1.016 1.016)
					(thickness 0.1524)
				)
			)
		)
		(duplicate_pad_numbers_are_jumpers no)
		(fp_line
			(start -1.016 -2.2352)
			(end 1.016 -2.2352)
			(stroke
				(width 0.1524)
				(type default)
			)
			(layer "F.SilkS")
		)
		(fp_line
			(start -1.016 2.2352)
			(end -1.016 -2.2352)
			(stroke
				(width 0.1524)
				(type default)
			)
			(layer "F.SilkS")
		)
		(fp_line
			(start 1.016 -2.2352)
			(end 1.016 2.2352)
			(stroke
				(width 0.1524)
				(type default)
			)
			(layer "F.SilkS")
		)
		(fp_line
			(start 1.016 2.2352)
			(end -1.016 2.2352)
			(stroke
				(width 0.1524)
				(type default)
			)
			(layer "F.SilkS")
		)
		(fp_rect
			(start -1.0922 2.3114)
			(end 1.0922 -2.3114)
			(stroke
				(width 0)
				(type default)
			)
			(fill no)
			(layer "F.CrtYd")
		)
		(fp_poly
			(pts
				(xy -1.0922 -2.3114) (xy 1.0922 -2.3114) (xy 1.0922 2.3114) (xy -1.0922 2.3114)
			)
			(stroke
				(width 0)
				(type default)
			)
			(fill no)
			(layer "F.Fab")
		)
		(pad "1" smd rect
			(at 0 -1.397)
			(size 1.651 1.27)
			(layers "F.Cu" "F.Mask" "F.Paste")
			(net "P5V_HDD12")
		)
		(pad "2" smd rect
			(at 0 1.397)
			(size 1.651 1.27)
			(layers "F.Cu" "F.Mask" "F.Paste")
			(net "5V_PRE_12")
		)
	)
)
